# SCM (Grand Teton) — schematic netlist excerpt (pin names and nets, part order shuffled) for the footprints in the layout excerpt that follows; sources: Cadence DE-HDL packaged netlist, KiCad conversion of 12092022_DA0F0TMDCD0_F0T_Management_Board_D_brd_V3_OCP.brd

C168  Q_CAP  0.1UF 25V 10% X7R  pkg 0402  page 20 : A = P0V6_DDR_VREF_AUX ; B = GND
R745  Q_RES  100 1% EMPTY  pkg 0402LF  page 28 : A = LED_POSTCODE_A2 ; B = GND

(kicad_pcb
	(version 20260206)
	(generator "pcbnew")
	(generator_version "10.0")
	(general
		(thickness 1.6)
		(legacy_teardrops no)
	)
	(paper "A4")
	(title_block
		(title "12092022_DA0F0TMDCD0_F0T_Management_Board_D_brd_V3_OCP.brd")
		(comment 1 "Grand Teton / footprints 1105-1106 of 1440")
	)
	(layers
		(0 "F.Cu" signal "TOP")
		(4 "In1.Cu" signal "GND")
		(6 "In2.Cu" signal "IN1")
		(8 "In3.Cu" signal "GND1")
		(10 "In4.Cu" signal "IN2")
		(12 "In5.Cu" signal "VCC")
		(14 "In6.Cu" signal "VCC1")
		(16 "In7.Cu" signal "IN3")
		(18 "In8.Cu" signal "GND2")
		(20 "In9.Cu" signal "IN4")
		(22 "In10.Cu" signal "GND3")
		(2 "B.Cu" signal "BOTTOM")
		(9 "F.Adhes" user "F.Adhesive")
		(11 "B.Adhes" user "B.Adhesive")
		(13 "F.Paste" user "Package Geometry/Pastemask Top")
		(15 "B.Paste" user "Package Geometry/Pastemask Bottom")
		(5 "F.SilkS" user "Ref Des/Silkscreen Top")
		(7 "B.SilkS" user "Ref Des/Silkscreen Bottom")
		(1 "F.Mask" user "Board Geometry/Soldermask Top")
		(3 "B.Mask" user "Board Geometry/Soldermask Bottom")
		(17 "Dwgs.User" user "User.Drawings")
		(19 "Cmts.User" user "User.Comments")
		(21 "Eco1.User" user "User.Eco1")
		(23 "Eco2.User" user "User.Eco2")
		(25 "Edge.Cuts" user "Board Geometry/Outline")
		(27 "Margin" user)
		(31 "F.CrtYd" user "Package Geometry/Place Bound Top")
		(29 "B.CrtYd" user "Package Geometry/Place Bound Bottom")
		(35 "F.Fab" user "Ref Des/Assembly Top")
		(33 "B.Fab" user "Ref Des/Assembly Bottom")
	)
	(footprint ""
		(layer "B.Cu")
		(at 84.08924 -52.397152 180)
		(property "Reference" "C168"
			(at 0 0 0)
			(layer "B.SilkS")
			(hide yes)
			(effects
				(font
					(size 1.27 1.27)
				)
				(justify mirror)
			)
		)
		(property "Value" ""
			(at 0 0 0)
			(layer "B.Fab")
			(effects
				(font
					(size 1.27 1.27)
				)
				(justify mirror)
			)
		)
		(duplicate_pad_numbers_are_jumpers no)
		(fp_line
			(start 0.7874 0.4064)
			(end 0.7874 -0.4064)
			(stroke
				(width 0.1524)
				(type default)
			)
			(layer "B.SilkS")
		)
		(fp_line
			(start 0.7874 -0.4064)
			(end -0.7874 -0.4064)
			(stroke
				(width 0.1524)
				(type default)
			)
			(layer "B.SilkS")
		)
		(fp_line
			(start -0.7874 0.4064)
			(end 0.7874 0.4064)
			(stroke
				(width 0.1524)
				(type default)
			)
			(layer "B.SilkS")
		)
		(fp_line
			(start -0.7874 -0.4064)
			(end -0.7874 0.4064)
			(stroke
				(width 0.1524)
				(type default)
			)
			(layer "B.SilkS")
		)
		(fp_line
			(start 0.67945 0.3048)
			(end 0.67945 -0.305054)
			(stroke
				(width 0.1)
				(type default)
			)
			(layer "B.Fab")
		)
		(fp_line
			(start 0.67945 -0.305054)
			(end 0.12065 -0.305054)
			(stroke
				(width 0.1)
				(type default)
			)
			(layer "B.Fab")
		)
		(fp_line
			(start 0.12065 0.3048)
			(end 0.67945 0.3048)
			(stroke
				(width 0.1)
				(type default)
			)
			(layer "B.Fab")
		)
		(fp_line
			(start 0.12065 0.2794)
			(end 0.12065 0.3048)
			(stroke
				(width 0.1)
				(type default)
			)
			(layer "B.Fab")
		)
		(fp_line
			(start 0.12065 -0.2794)
			(end -0.12065 -0.2794)
			(stroke
				(width 0.1)
				(type default)
			)
			(layer "B.Fab")
		)
		(fp_line
			(start 0.12065 -0.305054)
			(end 0.12065 -0.2794)
			(stroke
				(width 0.1)
				(type default)
			)
			(layer "B.Fab")
		)
		(fp_line
			(start -0.120396 0.3048)
			(end -0.120396 0.2794)
			(stroke
				(width 0.1)
				(type default)
			)
			(layer "B.Fab")
		)
		(fp_line
			(start -0.120396 0.2794)
			(end 0.12065 0.2794)
			(stroke
				(width 0.1)
				(type default)
			)
			(layer "B.Fab")
		)
		(fp_line
			(start -0.12065 -0.2794)
			(end -0.12065 -0.3048)
			(stroke
				(width 0.1)
				(type default)
			)
			(layer "B.Fab")
		)
		(fp_line
			(start -0.12065 -0.3048)
			(end -0.67945 -0.3048)
			(stroke
				(width 0.1)
				(type default)
			)
			(layer "B.Fab")
		)
		(fp_line
			(start -0.67945 0.3048)
			(end -0.120396 0.3048)
			(stroke
				(width 0.1)
				(type default)
			)
			(layer "B.Fab")
		)
		(fp_line
			(start -0.67945 -0.3048)
			(end -0.67945 0.3048)
			(stroke
				(width 0.1)
				(type default)
			)
			(layer "B.Fab")
		)
		(pad "1" smd circle
			(at 0.40005 0)
			(size 0 0)
			(layers "B.Cu" "B.Mask" "B.Paste")
			(net "P0V6_DDR_VREF_AUX")
		)
		(pad "2" smd circle
			(at -0.40005 0)
			(size 0 0)
			(layers "B.Cu" "B.Mask" "B.Paste")
			(net "GND")
		)
	)
	(footprint ""
		(layer "B.Cu")
		(at 63.9572 -89.2048 180)
		(property "Reference" "R745"
			(at 0 0 0)
			(layer "B.SilkS")
			(hide yes)
			(effects
				(font
					(size 1.27 1.27)
				)
				(justify mirror)
			)
		)
		(property "Value" ""
			(at 0 0 0)
			(layer "B.Fab")
			(effects
				(font
					(size 1.27 1.27)
				)
				(justify mirror)
			)
		)
		(duplicate_pad_numbers_are_jumpers no)
		(fp_line
			(start 0.7874 0.4064)
			(end 0.7874 -0.4064)
			(stroke
				(width 0.1524)
				(type default)
			)
			(layer "B.SilkS")
		)
		(fp_line
			(start 0.7874 -0.4064)
			(end -0.7874 -0.4064)
			(stroke
				(width 0.1524)
				(type default)
			)
			(layer "B.SilkS")
		)
		(fp_line
			(start -0.7874 0.4064)
			(end 0.7874 0.4064)
			(stroke
				(width 0.1524)
				(type default)
			)
			(layer "B.SilkS")
		)
		(fp_line
			(start -0.7874 -0.4064)
			(end -0.7874 0.4064)
			(stroke
				(width 0.1524)
				(type default)
			)
			(layer "B.SilkS")
		)
		(fp_line
			(start 0.67945 0.3048)
			(end 0.67945 -0.305054)
			(stroke
				(width 0.1)
				(type default)
			)
			(layer "B.Fab")
		)
		(fp_line
			(start 0.67945 -0.305054)
			(end 0.12065 -0.305054)
			(stroke
				(width 0.1)
				(type default)
			)
			(layer "B.Fab")
		)
		(fp_line
			(start 0.12065 0.3048)
			(end 0.67945 0.3048)
			(stroke
				(width 0.1)
				(type default)
			)
			(layer "B.Fab")
		)
		(fp_line
			(start 0.12065 0.2794)
			(end 0.12065 0.3048)
			(stroke
				(width 0.1)
				(type default)
			)
			(layer "B.Fab")
		)
		(fp_line
			(start 0.12065 -0.2794)
			(end -0.12065 -0.2794)
			(stroke
				(width 0.1)
				(type default)
			)
			(layer "B.Fab")
		)
		(fp_line
			(start 0.12065 -0.305054)
			(end 0.12065 -0.2794)
			(stroke
				(width 0.1)
				(type default)
			)
			(layer "B.Fab")
		)
		(fp_line
			(start -0.120396 0.3048)
			(end -0.120396 0.2794)
			(stroke
				(width 0.1)
				(type default)
			)
			(layer "B.Fab")
		)
		(fp_line
			(start -0.120396 0.2794)
			(end 0.12065 0.2794)
			(stroke
				(width 0.1)
				(type default)
			)
			(layer "B.Fab")
		)
		(fp_line
			(start -0.12065 -0.2794)
			(end -0.12065 -0.3048)
			(stroke
				(width 0.1)
				(type default)
			)
			(layer "B.Fab")
		)
		(fp_line
			(start -0.12065 -0.3048)
			(end -0.67945 -0.3048)
			(stroke
				(width 0.1)
				(type default)
			)
			(layer "B.Fab")
		)
		(fp_line
			(start -0.67945 0.3048)
			(end -0.120396 0.3048)
			(stroke
				(width 0.1)
				(type default)
			)
			(layer "B.Fab")
		)
		(fp_line
			(start -0.67945 -0.3048)
			(end -0.67945 0.3048)
			(stroke
				(width 0.1)
				(type default)
			)
			(layer "B.Fab")
		)
		(pad "1" smd circle
			(at 0.40005 0)
			(size 0 0)
			(layers "B.Cu" "B.Mask" "B.Paste")
			(net "LED_POSTCODE_A2")
		)
		(pad "2" smd circle
			(at -0.40005 0)
			(size 0 0)
			(layers "B.Cu" "B.Mask" "B.Paste")
			(net "GND")
		)
	)
)
